# TIMECARD (Time Appliance Project (Time Card)) — schematic netlist excerpt (pin names and nets, part order shuffled) for the footprints in the layout excerpt that follows; sources: Cadence DE-HDL packaged netlist, KiCad conversion of R4006-B0001-02_R01.brd

SP61  NULL  pkg DUMMY  page 34
R395  RESISTOR  33OHM 1%  pkg SMC_0402R_H016  page 26 : \1\ = SMA4_LED_GREEN_N ; \2\ = UNNAMED_14_LED4PV14_I268_4
TP183  TP_PIONT  pkg TP010CT020B030_PTH  page 25 : \1\ = IO_L22P_16

(kicad_pcb
	(version 20260206)
	(generator "pcbnew")
	(generator_version "10.0")
	(general
		(thickness 1.6)
		(legacy_teardrops no)
	)
	(paper "A4")
	(title_block
		(title "timecard-production-celestica-r4006 — R4006-B0001-02_R01.brd")
		(comment 1 "Time Appliance Project (Time Card) / footprints 510-512 of 1113")
	)
	(layers
		(0 "F.Cu" signal "TOP")
		(4 "In1.Cu" signal "L02_GND1")
		(6 "In2.Cu" signal "L03_SIG1")
		(8 "In3.Cu" signal "L04_GND2")
		(10 "In4.Cu" signal "L05_VCC1")
		(12 "In5.Cu" signal "L06_VCC2")
		(14 "In6.Cu" signal "L07_GND3")
		(16 "In7.Cu" signal "L08_SIG2")
		(18 "In8.Cu" signal "L09_GND4")
		(2 "B.Cu" signal "BOTTOM")
		(9 "F.Adhes" user "F.Adhesive")
		(11 "B.Adhes" user "B.Adhesive")
		(13 "F.Paste" user "Package Geometry/Pastemask Top")
		(15 "B.Paste" user "Package Geometry/Pastemask Bottom")
		(5 "F.SilkS" user "Ref Des/Silkscreen Top")
		(7 "B.SilkS" user "Ref Des/Silkscreen Bottom")
		(1 "F.Mask" user "Board Geometry/Soldermask Top")
		(3 "B.Mask" user "Board Geometry/Soldermask Bottom")
		(17 "Dwgs.User" user "User.Drawings")
		(19 "Cmts.User" user "User.Comments")
		(21 "Eco1.User" user "User.Eco1")
		(23 "Eco2.User" user "User.Eco2")
		(25 "Edge.Cuts" user "Board Geometry/Outline")
		(27 "Margin" user)
		(31 "F.CrtYd" user "Package Geometry/Place Bound Top")
		(29 "B.CrtYd" user "Package Geometry/Place Bound Bottom")
		(35 "F.Fab" user "Ref Des/Assembly Top")
		(33 "B.Fab" user "Ref Des/Assembly Bottom")
	)
	(footprint ""
		(layer "F.Cu")
		(at 19.468338 -49.022 180)
		(property "Reference" "R395"
			(at -3.518662 0.21463 0)
			(unlocked yes)
			(layer "F.SilkS")
			(effects
				(font
					(size 0.7874 0.5842)
					(thickness 0.1524)
				)
			)
		)
		(property "Value" "VAL*"
			(at 0.02032 2.13233 180)
			(unlocked yes)
			(layer "F.Fab")
			(hide yes)
			(effects
				(font
					(size 0.7874 0.5842)
					(thickness 0.1524)
				)
			)
		)
		(property "Tolerance" "TOL*"
			(at 0.044704 3.05435 180)
			(unlocked yes)
			(layer "Cmts.User")
			(hide yes)
			(effects
				(font
					(size 0.7874 0.5842)
					(thickness 0.1524)
				)
			)
		)
		(property "User Part Number" "PARTNUM*"
			(at 0.02032 4.024884 180)
			(unlocked yes)
			(layer "Cmts.User")
			(hide yes)
			(effects
				(font
					(size 0.7874 0.5842)
					(thickness 0.1524)
				)
			)
		)
		(property "Device Type" "RESISTOR-G155-133R0-01,33OHM,1%"
			(at 0.008382 1.210564 180)
			(unlocked yes)
			(layer "F.Fab")
			(hide yes)
			(effects
				(font
					(size 0.7874 0.5842)
					(thickness 0.1524)
				)
			)
		)
		(duplicate_pad_numbers_are_jumpers no)
		(fp_line
			(start 1.143 0.5588)
			(end 1.143 -0.5588)
			(stroke
				(width 0.1)
				(type default)
			)
			(layer "F.SilkS")
		)
		(fp_line
			(start 1.143 -0.5588)
			(end -1.143 -0.5588)
			(stroke
				(width 0.1)
				(type default)
			)
			(layer "F.SilkS")
		)
		(fp_line
			(start -1.143 0.5588)
			(end 1.143 0.5588)
			(stroke
				(width 0.1)
				(type default)
			)
			(layer "F.SilkS")
		)
		(fp_line
			(start -1.143 -0.5588)
			(end -1.143 0.5588)
			(stroke
				(width 0.1)
				(type default)
			)
			(layer "F.SilkS")
		)
		(fp_rect
			(start -1.143 -0.5588)
			(end 1.143 0.5588)
			(stroke
				(width 0)
				(type default)
			)
			(fill no)
			(layer "F.CrtYd")
		)
		(fp_line
			(start 0.508 0.3048)
			(end 0.508 -0.3048)
			(stroke
				(width 0.1)
				(type default)
			)
			(layer "F.Fab")
		)
		(fp_line
			(start 0.508 -0.3048)
			(end -0.508 -0.3048)
			(stroke
				(width 0.1)
				(type default)
			)
			(layer "F.Fab")
		)
		(fp_line
			(start -0.508 0.3048)
			(end 0.508 0.3048)
			(stroke
				(width 0.1)
				(type default)
			)
			(layer "F.Fab")
		)
		(fp_line
			(start -0.508 -0.3048)
			(end -0.508 0.3048)
			(stroke
				(width 0.1)
				(type default)
			)
			(layer "F.Fab")
		)
		(pad "1" smd rect
			(at -0.5334 0 180)
			(size 0.7112 0.6096)
			(layers "F.Cu" "F.Mask" "F.Paste")
			(net "SMA4_LED_GREEN_N")
		)
		(pad "2" smd rect
			(at 0.5334 0 180)
			(size 0.7112 0.6096)
			(layers "F.Cu" "F.Mask" "F.Paste")
			(net "UNNAMED_14_LED4PV14_I268_4")
		)
		(zone
			(layer "F.Cu")
			(hatch none 0.5)
			(connect_pads
				(clearance 0)
			)
			(min_thickness 0.25)
			(keepout
				(tracks not_allowed)
				(vias allowed)
				(pads allowed)
				(copperpour not_allowed)
				(footprints allowed)
			)
			(placement
				(enabled no)
				(sheetname "")
			)
			(fill
				(thermal_gap 0.5)
				(thermal_bridge_width 0.5)
				(island_removal_mode 0)
			)
			(polygon
				(pts
					(xy 19.544538 -48.7172) (xy 19.544538 -49.3268) (xy 19.392138 -49.3268) (xy 19.392138 -48.7172)
				)
			)
		)
		(zone
			(layer "F.Cu")
			(hatch none 0.5)
			(connect_pads
				(clearance 0)
			)
			(min_thickness 0.25)
			(keepout
				(tracks allowed)
				(vias not_allowed)
				(pads allowed)
				(copperpour not_allowed)
				(footprints allowed)
			)
			(placement
				(enabled no)
				(sheetname "")
			)
			(fill
				(thermal_gap 0.5)
				(thermal_bridge_width 0.5)
				(island_removal_mode 0)
			)
			(polygon
				(pts
					(xy 19.544538 -48.7172) (xy 19.544538 -49.3268) (xy 19.392138 -49.3268) (xy 19.392138 -48.7172)
				)
			)
		)
	)
	(footprint ""
		(layer "F.Cu")
		(at 105.3846 -58.3692)
		(property "Reference" "TP183"
			(at 3.74015 2.159 90)
			(unlocked yes)
			(layer "F.SilkS")
			(effects
				(font
					(size 0.635 0.4064)
					(thickness 0.1524)
				)
				(justify left)
			)
		)
		(property "Value" ""
			(at 0 0 0)
			(layer "F.Fab")
			(effects
				(font
					(size 1.27 1.27)
				)
			)
		)
		(property "Device Type" "TP_PIONT-TP010CT020B030_PTH-TPA"
			(at -1.341882 0.996696 0)
			(unlocked yes)
			(layer "F.Fab")
			(hide yes)
			(effects
				(font
					(size 0.7874 0.5842)
					(thickness 0.1524)
				)
				(justify left)
			)
		)
		(duplicate_pad_numbers_are_jumpers no)
		(fp_poly
			(pts
				(arc
					(start 0.889 0)
					(mid -0.889 0)
					(end 0.889 0)
				)
			)
			(stroke
				(width 0)
				(type default)
			)
			(fill no)
			(layer "B.CrtYd")
		)
		(fp_poly
			(pts
				(arc
					(start 0.889 0)
					(mid -0.889 0)
					(end 0.889 0)
				)
			)
			(stroke
				(width 0)
				(type default)
			)
			(fill no)
			(layer "F.CrtYd")
		)
		(pad "1" thru_hole circle
			(at 0 0)
			(size 0.508 0.508)
			(drill 0.254)
			(layers "*.Cu" "*.Mask")
			(remove_unused_layers no)
			(net "IO_L22P_16")
			(clearance 0.1016)
			(padstack
				(mode front_inner_back)
				(layer "Inner"
					(shape circle)
					(size 0.508 0.508)
					(clearance 0.1016)
				)
				(layer "B.Cu"
					(shape circle)
					(size 0.762 0.762)
					(clearance -0.0254)
				)
			)
		)
	)
	(footprint ""
		(layer "F.Cu")
		(at 50.673 -131.826)
		(property "Reference" "SP61"
			(at 0 0 0)
			(layer "F.SilkS")
			(hide yes)
			(effects
				(font
					(size 1.27 1.27)
				)
			)
		)
		(property "Value" ""
			(at 0 0 0)
			(layer "F.Fab")
			(effects
				(font
					(size 1.27 1.27)
				)
			)
		)
		(duplicate_pad_numbers_are_jumpers no)
	)
)
